# T6G (Grand Teton) — schematic netlist excerpt (pin names and nets, part order shuffled) for the footprints in the layout excerpt that follows; sources: Cadence DE-HDL packaged netlist, KiCad conversion of 04192023_DAF0TMB3IC0_F0TG_MB_C_brd_V02_OCP.brd

R3873  Q_RES  0 5% CHIP  pkg 0402LF  page 141 : A = P12V_OCP_IMON_2 ; B = P12V_OCP_V3_2_ISENSE_MPS_MAM

U54  PI4ULS3V304AZMAEX  IC  pkg UQFN12_0-4_2X1-7  page 77
  VCCA  = PVDD18_S5_P0
  A1  = SPI_CPU0_R1_D3
  A2  = SPI_CPU0_R1_D2
  A3  = SPI_CPU0_R1_D0
  A4  = SPI_CPU0_R1_D1
  GND  = GND
  B4  = SPI_CPU0_LVC3_D1
  B3  = SPI_CPU0_LVC3_D0
  B2  = SPI_CPU0_LVC3_D2
  B1  = SPI_CPU0_LVC3_D3
  VCCB  = P3V3_AUX
  EN  = ROM_LS_EN

(kicad_pcb
	(version 20260206)
	(generator "pcbnew")
	(generator_version "10.0")
	(general
		(thickness 1.6)
		(legacy_teardrops no)
	)
	(paper "A4")
	(title_block
		(title "04192023_DAF0TMB3IC0_F0TG_MB_C_brd_V02_OCP.brd")
		(comment 1 "Grand Teton / footprints 3590-3591 of 8354")
	)
	(layers
		(0 "F.Cu" signal "TOP")
		(4 "In1.Cu" signal "GND")
		(6 "In2.Cu" signal "IN1")
		(8 "In3.Cu" signal "GND1")
		(10 "In4.Cu" signal "IN2")
		(12 "In5.Cu" signal "GND2")
		(14 "In6.Cu" signal "IN3")
		(16 "In7.Cu" signal "GND3")
		(18 "In8.Cu" signal "VCC")
		(20 "In9.Cu" signal "VCC1")
		(22 "In10.Cu" signal "GND4")
		(24 "In11.Cu" signal "IN4")
		(26 "In12.Cu" signal "GND5")
		(28 "In13.Cu" signal "IN5")
		(30 "In14.Cu" signal "GND6")
		(32 "In15.Cu" signal "IN6")
		(34 "In16.Cu" signal "GND7")
		(2 "B.Cu" signal "BOTTOM")
		(9 "F.Adhes" user "F.Adhesive")
		(11 "B.Adhes" user "B.Adhesive")
		(13 "F.Paste" user "Package Geometry/Pastemask Top")
		(15 "B.Paste" user "Package Geometry/Pastemask Bottom")
		(5 "F.SilkS" user "Ref Des/Silkscreen Top")
		(7 "B.SilkS" user "Ref Des/Silkscreen Bottom")
		(1 "F.Mask" user "Board Geometry/Soldermask Top")
		(3 "B.Mask" user "Board Geometry/Soldermask Bottom")
		(17 "Dwgs.User" user "User.Drawings")
		(19 "Cmts.User" user "User.Comments")
		(21 "Eco1.User" user "User.Eco1")
		(23 "Eco2.User" user "User.Eco2")
		(25 "Edge.Cuts" user "Board Geometry/Outline")
		(27 "Margin" user)
		(31 "F.CrtYd" user "Package Geometry/Place Bound Top")
		(29 "B.CrtYd" user "Package Geometry/Place Bound Bottom")
		(35 "F.Fab" user "Ref Des/Assembly Top")
		(33 "B.Fab" user "Ref Des/Assembly Bottom")
	)
	(footprint ""
		(layer "F.Cu")
		(at 260.99008 -138.848846 180)
		(property "Reference" "U54"
			(at 1.0033 -2.747264 0)
			(unlocked yes)
			(layer "F.SilkS")
			(effects
				(font
					(size 0.7874 0.5842)
					(thickness 0.1524)
				)
				(justify left)
			)
		)
		(property "Value" ""
			(at 0 0 180)
			(layer "F.Fab")
			(effects
				(font
					(size 1.27 1.27)
				)
			)
		)
		(duplicate_pad_numbers_are_jumpers no)
		(fp_line
			(start 1.145286 1.2954)
			(end 1.145286 -1.2954)
			(stroke
				(width 0.1524)
				(type default)
			)
			(layer "F.SilkS")
		)
		(fp_line
			(start 1.145286 -1.2954)
			(end -1.145286 -1.2954)
			(stroke
				(width 0.1524)
				(type default)
			)
			(layer "F.SilkS")
		)
		(fp_line
			(start -1.145286 1.2954)
			(end 1.145286 1.2954)
			(stroke
				(width 0.1524)
				(type default)
			)
			(layer "F.SilkS")
		)
		(fp_line
			(start -1.145286 -1.2954)
			(end -1.145286 1.2954)
			(stroke
				(width 0.1524)
				(type default)
			)
			(layer "F.SilkS")
		)
		(fp_poly
			(pts
				(xy -0.804926 -1.442466) (xy -1.058926 -1.950466) (xy -0.550926 -1.950466)
			)
			(stroke
				(width 0)
				(type default)
			)
			(fill yes)
			(layer "F.SilkS")
		)
		(fp_line
			(start 0.87503 1.02489)
			(end 0.87503 -1.02489)
			(stroke
				(width 0.1)
				(type default)
			)
			(layer "F.Fab")
		)
		(fp_line
			(start 0.87503 -1.02489)
			(end -0.87503 -1.02489)
			(stroke
				(width 0.1)
				(type default)
			)
			(layer "F.Fab")
		)
		(fp_line
			(start -0.87503 1.02489)
			(end 0.87503 1.02489)
			(stroke
				(width 0.1)
				(type default)
			)
			(layer "F.Fab")
		)
		(fp_line
			(start -0.87503 -1.02489)
			(end -0.87503 1.02489)
			(stroke
				(width 0.1)
				(type default)
			)
			(layer "F.Fab")
		)
		(fp_poly
			(pts
				(xy -1.9304 -1.0541) (xy -1.9304 -0.5461) (xy -1.4224 -0.8001)
			)
			(stroke
				(width 0)
				(type default)
			)
			(fill yes)
			(layer "F.Fab")
		)
		(pad "1" smd rect
			(at -0.649986 -0.8001 270)
			(size 0.1778 0.7112)
			(layers "F.Cu" "F.Mask" "F.Paste")
			(net "PVDD18_S5_P0")
		)
		(pad "2" smd rect
			(at -0.649986 -0.40005 270)
			(size 0.1778 0.7112)
			(layers "F.Cu" "F.Mask" "F.Paste")
			(net "SPI_CPU0_R1_D3")
		)
		(pad "3" smd rect
			(at -0.649986 0 270)
			(size 0.1778 0.7112)
			(layers "F.Cu" "F.Mask" "F.Paste")
			(net "SPI_CPU0_R1_D2")
		)
		(pad "4" smd rect
			(at -0.649986 0.40005 270)
			(size 0.1778 0.7112)
			(layers "F.Cu" "F.Mask" "F.Paste")
			(net "SPI_CPU0_R1_D0")
		)
		(pad "5" smd rect
			(at -0.649986 0.8001 270)
			(size 0.1778 0.7112)
			(layers "F.Cu" "F.Mask" "F.Paste")
			(net "SPI_CPU0_R1_D1")
		)
		(pad "6" smd rect
			(at 0 0.8001 180)
			(size 0.1778 0.7112)
			(layers "F.Cu" "F.Mask" "F.Paste")
			(net "GND")
		)
		(pad "7" smd rect
			(at 0.649986 0.8001 270)
			(size 0.1778 0.7112)
			(layers "F.Cu" "F.Mask" "F.Paste")
			(net "SPI_CPU0_LVC3_D1")
		)
		(pad "8" smd rect
			(at 0.649986 0.40005 270)
			(size 0.1778 0.7112)
			(layers "F.Cu" "F.Mask" "F.Paste")
			(net "SPI_CPU0_LVC3_D0")
		)
		(pad "9" smd rect
			(at 0.649986 0 270)
			(size 0.1778 0.7112)
			(layers "F.Cu" "F.Mask" "F.Paste")
			(net "SPI_CPU0_LVC3_D2")
		)
		(pad "10" smd rect
			(at 0.649986 -0.40005 270)
			(size 0.1778 0.7112)
			(layers "F.Cu" "F.Mask" "F.Paste")
			(net "SPI_CPU0_LVC3_D3")
		)
		(pad "11" smd rect
			(at 0.649986 -0.8001 270)
			(size 0.1778 0.7112)
			(layers "F.Cu" "F.Mask" "F.Paste")
			(net "P3V3_AUX")
		)
		(pad "12" smd rect
			(at 0 -0.8001 180)
			(size 0.1778 0.7112)
			(layers "F.Cu" "F.Mask" "F.Paste")
			(net "ROM_LS_EN")
		)
	)
	(footprint ""
		(layer "F.Cu")
		(at 62.559438 -31.887922 90)
		(property "Reference" "R3873"
			(at 0 0 90)
			(layer "F.SilkS")
			(hide yes)
			(effects
				(font
					(size 1.27 1.27)
				)
			)
		)
		(property "Value" ""
			(at 0 0 90)
			(layer "F.Fab")
			(effects
				(font
					(size 1.27 1.27)
				)
			)
		)
		(duplicate_pad_numbers_are_jumpers no)
		(fp_line
			(start 0.7874 -0.4064)
			(end 0.7874 0.4064)
			(stroke
				(width 0.1524)
				(type default)
			)
			(layer "F.SilkS")
		)
		(fp_line
			(start -0.7874 -0.4064)
			(end 0.7874 -0.4064)
			(stroke
				(width 0.1524)
				(type default)
			)
			(layer "F.SilkS")
		)
		(fp_line
			(start 0.7874 0.4064)
			(end -0.7874 0.4064)
			(stroke
				(width 0.1524)
				(type default)
			)
			(layer "F.SilkS")
		)
		(fp_line
			(start -0.7874 0.4064)
			(end -0.7874 -0.4064)
			(stroke
				(width 0.1524)
				(type default)
			)
			(layer "F.SilkS")
		)
		(fp_line
			(start -0.12065 -0.305054)
			(end -0.12065 -0.2794)
			(stroke
				(width 0.1)
				(type default)
			)
			(layer "F.Fab")
		)
		(fp_line
			(start -0.67945 -0.305054)
			(end -0.12065 -0.305054)
			(stroke
				(width 0.1)
				(type default)
			)
			(layer "F.Fab")
		)
		(fp_line
			(start 0.67945 -0.3048)
			(end 0.67945 0.3048)
			(stroke
				(width 0.1)
				(type default)
			)
			(layer "F.Fab")
		)
		(fp_line
			(start 0.12065 -0.3048)
			(end 0.67945 -0.3048)
			(stroke
				(width 0.1)
				(type default)
			)
			(layer "F.Fab")
		)
		(fp_line
			(start 0.12065 -0.2794)
			(end 0.12065 -0.3048)
			(stroke
				(width 0.1)
				(type default)
			)
			(layer "F.Fab")
		)
		(fp_line
			(start -0.12065 -0.2794)
			(end 0.12065 -0.2794)
			(stroke
				(width 0.1)
				(type default)
			)
			(layer "F.Fab")
		)
		(fp_line
			(start 0.120396 0.2794)
			(end -0.12065 0.2794)
			(stroke
				(width 0.1)
				(type default)
			)
			(layer "F.Fab")
		)
		(fp_line
			(start -0.12065 0.2794)
			(end -0.12065 0.3048)
			(stroke
				(width 0.1)
				(type default)
			)
			(layer "F.Fab")
		)
		(fp_line
			(start 0.67945 0.3048)
			(end 0.120396 0.3048)
			(stroke
				(width 0.1)
				(type default)
			)
			(layer "F.Fab")
		)
		(fp_line
			(start 0.120396 0.3048)
			(end 0.120396 0.2794)
			(stroke
				(width 0.1)
				(type default)
			)
			(layer "F.Fab")
		)
		(fp_line
			(start -0.12065 0.3048)
			(end -0.67945 0.3048)
			(stroke
				(width 0.1)
				(type default)
			)
			(layer "F.Fab")
		)
		(fp_line
			(start -0.67945 0.3048)
			(end -0.67945 -0.305054)
			(stroke
				(width 0.1)
				(type default)
			)
			(layer "F.Fab")
		)
		(pad "1" smd circle
			(at -0.40005 0 90)
			(size 0 0)
			(layers "F.Cu" "F.Mask" "F.Paste")
			(net "P12V_OCP_IMON_2")
		)
		(pad "2" smd circle
			(at 0.40005 0 90)
			(size 0 0)
			(layers "F.Cu" "F.Mask" "F.Paste")
			(net "P12V_OCP_V3_2_ISENSE_MPS_MAM")
		)
	)
)
